#ISCELL
  pure_quanta quanta_title_block_c *
  *
#CELL
  pure_quanta genoa_sp5 *
  page25_i147
#CELL
  pure_quanta genoa_sp5 *
  page25_i148
#ISCELL
  standard offpage *
  page25_i149
#ISCELL
  standard offpage *
  page25_i150
#ISCELL
  mstr_standard tap *
  page25_i151
#ISCELL
  mstr_standard tap *
  page25_i152
#ISCELL
  mstr_standard tap *
  page25_i153
#ISCELL
  mstr_standard tap *
  page25_i154
#ISCELL
  standard tap *
  page25_i155
#ISCELL
  standard tap *
  page25_i156
#ISCELL
  standard tap *
  page25_i157
#ISCELL
  standard tap *
  page25_i158
#ISCELL
  standard tap *
  page25_i159
#ISCELL
  standard tap *
  page25_i160
#ISCELL
  standard tap *
  page25_i161
#ISCELL
  standard tap *
  page25_i162
#ISCELL
  standard tap *
  page25_i163
#ISCELL
  standard tap *
  page25_i164
#ISCELL
  standard tap *
  page25_i165
#ISCELL
  standard tap *
  page25_i166
#ISCELL
  standard tap *
  page25_i167
#ISCELL
  standard tap *
  page25_i168
#ISCELL
  standard tap *
  page25_i169
#ISCELL
  standard tap *
  page25_i170
#ISCELL
  standard tap *
  page25_i171
#ISCELL
  standard tap *
  page25_i172
#ISCELL
  standard tap *
  page25_i173
#ISCELL
  standard tap *
  page25_i174
#ISCELL
  standard tap *
  page25_i175
#ISCELL
  standard tap *
  page25_i176
#ISCELL
  standard tap *
  page25_i177
#ISCELL
  standard tap *
  page25_i178
#ISCELL
  standard tap *
  page25_i179
#ISCELL
  standard tap *
  page25_i180
#ISCELL
  standard tap *
  page25_i181
#ISCELL
  standard tap *
  page25_i182
#ISCELL
  mstr_standard tap *
  page25_i325
#ISCELL
  mstr_standard tap *
  page25_i326
#ISCELL
  mstr_standard tap *
  page25_i327
#ISCELL
  mstr_standard tap *
  page25_i328
#ISCELL
  mstr_standard tap *
  page25_i329
#ISCELL
  standard tap *
  page25_i330
#ISCELL
  standard tap *
  page25_i331
#ISCELL
  standard tap *
  page25_i332
#ISCELL
  standard tap *
  page25_i333
#ISCELL
  standard tap *
  page25_i334
#ISCELL
  standard tap *
  page25_i335
#ISCELL
  standard tap *
  page25_i336
#ISCELL
  standard tap *
  page25_i337
#ISCELL
  standard tap *
  page25_i338
#ISCELL
  standard tap *
  page25_i339
#ISCELL
  standard tap *
  page25_i340
#ISCELL
  standard tap *
  page25_i341
#ISCELL
  standard tap *
  page25_i342
#ISCELL
  standard tap *
  page25_i343
#ISCELL
  standard tap *
  page25_i344
#ISCELL
  standard tap *
  page25_i345
#ISCELL
  standard tap *
  page25_i346
#ISCELL
  standard tap *
  page25_i347
#ISCELL
  standard tap *
  page25_i348
#ISCELL
  standard tap *
  page25_i349
#ISCELL
  standard tap *
  page25_i350
#ISCELL
  standard tap *
  page25_i351
#ISCELL
  standard tap *
  page25_i352
#ISCELL
  standard tap *
  page25_i353
#ISCELL
  standard tap *
  page25_i354
#ISCELL
  standard tap *
  page25_i355
#ISCELL
  standard tap *
  page25_i356
#ISCELL
  standard offpage *
  page25_i357
#ISCELL
  standard offpage *
  page25_i358
#ISCELL
  mstr_standard tap *
  page25_i359
#ISCELL
  mstr_standard tap *
  page25_i360
#ISCELL
  mstr_standard tap *
  page25_i361
#ISCELL
  mstr_standard tap *
  page25_i362
#ISCELL
  mstr_standard tap *
  page25_i363
#ISCELL
  standard tap *
  page25_i364
#ISCELL
  standard tap *
  page25_i365
#ISCELL
  standard tap *
  page25_i366
#ISCELL
  standard tap *
  page25_i367
#ISCELL
  standard tap *
  page25_i368
#ISCELL
  standard tap *
  page25_i369
#ISCELL
  standard tap *
  page25_i370
#ISCELL
  standard tap *
  page25_i371
#ISCELL
  standard tap *
  page25_i372
#ISCELL
  standard tap *
  page25_i373
#ISCELL
  standard tap *
  page25_i374
#ISCELL
  standard tap *
  page25_i375
#ISCELL
  standard tap *
  page25_i376
#ISCELL
  standard tap *
  page25_i377
#ISCELL
  standard tap *
  page25_i378
#ISCELL
  standard tap *
  page25_i379
#ISCELL
  standard tap *
  page25_i380
#ISCELL
  standard tap *
  page25_i381
#ISCELL
  standard tap *
  page25_i382
#ISCELL
  standard tap *
  page25_i383
#ISCELL
  standard tap *
  page25_i384
#ISCELL
  standard tap *
  page25_i385
#ISCELL
  standard tap *
  page25_i386
#ISCELL
  standard tap *
  page25_i387
#ISCELL
  standard tap *
  page25_i388
#ISCELL
  standard tap *
  page25_i389
#ISCELL
  standard tap *
  page25_i390
#ISCELL
  standard offpage *
  page25_i391
#ISCELL
  standard offpage *
  page25_i392
#ISCELL
  mstr_standard tap *
  page25_i393
#ISCELL
  mstr_standard tap *
  page25_i394
#ISCELL
  mstr_standard tap *
  page25_i395
#ISCELL
  mstr_standard tap *
  page25_i396
#ISCELL
  standard tap *
  page25_i397
#ISCELL
  standard tap *
  page25_i398
#ISCELL
  standard tap *
  page25_i399
#ISCELL
  standard tap *
  page25_i400
#ISCELL
  standard tap *
  page25_i401
#ISCELL
  standard tap *
  page25_i402
#ISCELL
  standard tap *
  page25_i403
#ISCELL
  standard tap *
  page25_i404
#ISCELL
  standard tap *
  page25_i405
#ISCELL
  standard tap *
  page25_i406
#ISCELL
  standard tap *
  page25_i407
#ISCELL
  standard tap *
  page25_i408
#ISCELL
  standard tap *
  page25_i409
#ISCELL
  standard tap *
  page25_i410
#ISCELL
  standard tap *
  page25_i411
#ISCELL
  standard tap *
  page25_i412
#ISCELL
  standard tap *
  page25_i413
#ISCELL
  standard tap *
  page25_i414
#ISCELL
  standard tap *
  page25_i415
#ISCELL
  standard tap *
  page25_i416
#ISCELL
  standard tap *
  page25_i417
#ISCELL
  standard tap *
  page25_i418
#ISCELL
  standard tap *
  page25_i419
#ISCELL
  standard tap *
  page25_i420
#ISCELL
  standard tap *
  page25_i421
#ISCELL
  standard tap *
  page25_i422
#ISCELL
  standard tap *
  page25_i423
#ISCELL
  standard tap *
  page25_i424
#ISCELL
  standard offpage *
  page25_i425
#ISCELL
  standard offpage *
  page25_i426
